(kicad_pcb
	(version 20260206)
	(generator "pcbnew")
	(generator_version "10.0")
	(general
		(thickness 1.6)
		(legacy_teardrops no)
	)
	(paper "A4")
	(title_block
		(title "03242023_DA0F0TMBIJ0_F0T_Motherboard_J_brd_V01_OCP.brd")
		(comment 1 "Grand Teton / footprint 1690 of 6105 (J16), pads 225-291 of 291")
	)
	(layers
		(0 "F.Cu" signal "TOP")
		(4 "In1.Cu" signal "GND")
		(6 "In2.Cu" signal "IN1")
		(8 "In3.Cu" signal "GND1")
		(10 "In4.Cu" signal "IN2")
		(12 "In5.Cu" signal "GND2")
		(14 "In6.Cu" signal "IN3")
		(16 "In7.Cu" signal "GND3")
		(18 "In8.Cu" signal "VCC")
		(20 "In9.Cu" signal "VCC1")
		(22 "In10.Cu" signal "GND4")
		(24 "In11.Cu" signal "IN4")
		(26 "In12.Cu" signal "GND5")
		(28 "In13.Cu" signal "IN5")
		(30 "In14.Cu" signal "GND6")
		(32 "In15.Cu" signal "IN6")
		(34 "In16.Cu" signal "GND7")
		(2 "B.Cu" signal "BOTTOM")
		(9 "F.Adhes" user "F.Adhesive")
		(11 "B.Adhes" user "B.Adhesive")
		(13 "F.Paste" user "Package Geometry/Pastemask Top")
		(15 "B.Paste" user "Package Geometry/Pastemask Bottom")
		(5 "F.SilkS" user "Ref Des/Silkscreen Top")
		(7 "B.SilkS" user "Ref Des/Silkscreen Bottom")
		(1 "F.Mask" user "Board Geometry/Soldermask Top")
		(3 "B.Mask" user "Board Geometry/Soldermask Bottom")
		(17 "Dwgs.User" user "User.Drawings")
		(19 "Cmts.User" user "User.Comments")
		(21 "Eco1.User" user "User.Eco1")
		(23 "Eco2.User" user "User.Eco2")
		(25 "Edge.Cuts" user "Board Geometry/Outline")
		(27 "Margin" user)
		(31 "F.CrtYd" user "Package Geometry/Place Bound Top")
		(29 "B.CrtYd" user "Package Geometry/Place Bound Bottom")
		(35 "F.Fab" user "Ref Des/Assembly Top")
		(33 "B.Fab" user "Ref Des/Assembly Bottom")
	)
	(footprint ""
		(layer "F.Cu")
		(at 454.066148 -258.091686)
		(property "Reference" "J16"
			(at -0.279908 -81.779872 0)
			(unlocked yes)
			(layer "F.SilkS")
			(effects
				(font
					(size 0.7874 0.5842)
					(thickness 0.1524)
				)
				(justify left)
			)
		)
		(property "Value" ""
			(at 0 0 0)
			(layer "F.Fab")
			(effects
				(font
					(size 1.27 1.27)
				)
			)
		)
		(duplicate_pad_numbers_are_jumpers no)
		(pad "225" smd rect
			(at 2.050034 9.774936 270)
			(size 0.519938 1.4986)
			(layers "F.Cu" "F.Mask" "F.Paste")
			(net "M_H_CPU0_SB_CA<5>")
		)
		(pad "226" smd rect
			(at 2.050034 10.625074 270)
			(size 0.519938 1.4986)
			(layers "F.Cu" "F.Mask" "F.Paste")
			(net "GND")
		)
		(pad "227" smd rect
			(at 2.050034 11.474958 270)
			(size 0.519938 1.4986)
			(layers "F.Cu" "F.Mask" "F.Paste")
			(net "M_H_CPU0_SB_PAR")
		)
		(pad "228" smd rect
			(at 2.050034 12.325096 270)
			(size 0.519938 1.4986)
			(layers "F.Cu" "F.Mask" "F.Paste")
			(net "GND")
		)
		(pad "229" smd rect
			(at 2.050034 13.17498 270)
			(size 0.519938 1.4986)
			(layers "F.Cu" "F.Mask" "F.Paste")
			(net "M_H_CPU0_SB_CS_N<3>")
		)
		(pad "230" smd rect
			(at 2.050034 14.025118 270)
			(size 0.519938 1.4986)
			(layers "F.Cu" "F.Mask" "F.Paste")
			(net "GND")
		)
		(pad "231" smd rect
			(at 2.050034 14.875002 270)
			(size 0.519938 1.4986)
			(layers "F.Cu" "F.Mask" "F.Paste")
			(net "TP_CHH_CPU0_DIMM2_FRU_5")
		)
		(pad "232" smd rect
			(at 2.050034 15.724886 270)
			(size 0.519938 1.4986)
			(layers "F.Cu" "F.Mask" "F.Paste")
			(net "TP_CHH_CPU0_DIMM2_FRU_6")
		)
		(pad "233" smd rect
			(at 2.050034 16.575024 270)
			(size 0.519938 1.4986)
			(layers "F.Cu" "F.Mask" "F.Paste")
			(net "GND")
		)
		(pad "234" smd rect
			(at 2.050034 17.424908 270)
			(size 0.519938 1.4986)
			(layers "F.Cu" "F.Mask" "F.Paste")
			(net "M_H_CPU0_SB_CB<6>")
		)
		(pad "235" smd rect
			(at 2.050034 18.275046 270)
			(size 0.519938 1.4986)
			(layers "F.Cu" "F.Mask" "F.Paste")
			(net "GND")
		)
		(pad "236" smd rect
			(at 2.050034 19.12493 270)
			(size 0.519938 1.4986)
			(layers "F.Cu" "F.Mask" "F.Paste")
			(net "M_H_CPU0_SB_CB<7>")
		)
		(pad "237" smd rect
			(at 2.050034 19.975068 270)
			(size 0.519938 1.4986)
			(layers "F.Cu" "F.Mask" "F.Paste")
			(net "GND")
		)
		(pad "238" smd rect
			(at 2.050034 20.824952 270)
			(size 0.519938 1.4986)
			(layers "F.Cu" "F.Mask" "F.Paste")
			(net "M_H_CPU0_SB_DQS_DN<4>")
		)
		(pad "239" smd rect
			(at 2.050034 21.67509 270)
			(size 0.519938 1.4986)
			(layers "F.Cu" "F.Mask" "F.Paste")
			(net "M_H_CPU0_SB_DQS_DP<4>")
		)
		(pad "240" smd rect
			(at 2.050034 22.524974 270)
			(size 0.519938 1.4986)
			(layers "F.Cu" "F.Mask" "F.Paste")
			(net "GND")
		)
		(pad "241" smd rect
			(at 2.050034 23.375112 270)
			(size 0.519938 1.4986)
			(layers "F.Cu" "F.Mask" "F.Paste")
			(net "M_H_CPU0_SB_CB<2>")
		)
		(pad "242" smd rect
			(at 2.050034 24.224996 270)
			(size 0.519938 1.4986)
			(layers "F.Cu" "F.Mask" "F.Paste")
			(net "GND")
		)
		(pad "243" smd rect
			(at 2.050034 25.07488 270)
			(size 0.519938 1.4986)
			(layers "F.Cu" "F.Mask" "F.Paste")
			(net "M_H_CPU0_SB_CB<3>")
		)
		(pad "244" smd rect
			(at 2.050034 25.925018 270)
			(size 0.519938 1.4986)
			(layers "F.Cu" "F.Mask" "F.Paste")
			(net "GND")
		)
		(pad "245" smd rect
			(at 2.050034 26.774902 270)
			(size 0.519938 1.4986)
			(layers "F.Cu" "F.Mask" "F.Paste")
			(net "M_H_CPU0_SB_DQ<2>")
		)
		(pad "246" smd rect
			(at 2.050034 27.62504 270)
			(size 0.519938 1.4986)
			(layers "F.Cu" "F.Mask" "F.Paste")
			(net "GND")
		)
		(pad "247" smd rect
			(at 2.050034 28.474924 270)
			(size 0.519938 1.4986)
			(layers "F.Cu" "F.Mask" "F.Paste")
			(net "M_H_CPU0_SB_DQ<3>")
		)
		(pad "248" smd rect
			(at 2.050034 29.325062 270)
			(size 0.519938 1.4986)
			(layers "F.Cu" "F.Mask" "F.Paste")
			(net "GND")
		)
		(pad "249" smd rect
			(at 2.050034 30.174946 270)
			(size 0.519938 1.4986)
			(layers "F.Cu" "F.Mask" "F.Paste")
			(net "M_H_CPU0_SB_DQS_DN<5>")
		)
		(pad "250" smd rect
			(at 2.050034 31.025084 270)
			(size 0.519938 1.4986)
			(layers "F.Cu" "F.Mask" "F.Paste")
			(net "M_H_CPU0_SB_DQS_DP<5>")
		)
		(pad "251" smd rect
			(at 2.050034 31.874968 270)
			(size 0.519938 1.4986)
			(layers "F.Cu" "F.Mask" "F.Paste")
			(net "GND")
		)
		(pad "252" smd rect
			(at 2.050034 32.725106 270)
			(size 0.519938 1.4986)
			(layers "F.Cu" "F.Mask" "F.Paste")
			(net "M_H_CPU0_SB_DQ<6>")
		)
		(pad "253" smd rect
			(at 2.050034 33.57499 270)
			(size 0.519938 1.4986)
			(layers "F.Cu" "F.Mask" "F.Paste")
			(net "GND")
		)
		(pad "254" smd rect
			(at 2.050034 34.425128 270)
			(size 0.519938 1.4986)
			(layers "F.Cu" "F.Mask" "F.Paste")
			(net "M_H_CPU0_SB_DQ<7>")
		)
		(pad "255" smd rect
			(at 2.050034 35.275012 270)
			(size 0.519938 1.4986)
			(layers "F.Cu" "F.Mask" "F.Paste")
			(net "GND")
		)
		(pad "256" smd rect
			(at 2.050034 36.124896 270)
			(size 0.519938 1.4986)
			(layers "F.Cu" "F.Mask" "F.Paste")
			(net "M_H_CPU0_SB_DQ<10>")
		)
		(pad "257" smd rect
			(at 2.050034 36.975034 270)
			(size 0.519938 1.4986)
			(layers "F.Cu" "F.Mask" "F.Paste")
			(net "GND")
		)
		(pad "258" smd rect
			(at 2.050034 37.824918 270)
			(size 0.519938 1.4986)
			(layers "F.Cu" "F.Mask" "F.Paste")
			(net "M_H_CPU0_SB_DQ<11>")
		)
		(pad "259" smd rect
			(at 2.050034 38.675056 270)
			(size 0.519938 1.4986)
			(layers "F.Cu" "F.Mask" "F.Paste")
			(net "GND")
		)
		(pad "260" smd rect
			(at 2.050034 39.52494 270)
			(size 0.519938 1.4986)
			(layers "F.Cu" "F.Mask" "F.Paste")
			(net "M_H_CPU0_SB_DQS_DN<6>")
		)
		(pad "261" smd rect
			(at 2.050034 40.375078 270)
			(size 0.519938 1.4986)
			(layers "F.Cu" "F.Mask" "F.Paste")
			(net "M_H_CPU0_SB_DQS_DP<6>")
		)
		(pad "262" smd rect
			(at 2.050034 41.224962 270)
			(size 0.519938 1.4986)
			(layers "F.Cu" "F.Mask" "F.Paste")
			(net "GND")
		)
		(pad "263" smd rect
			(at 2.050034 42.0751 270)
			(size 0.519938 1.4986)
			(layers "F.Cu" "F.Mask" "F.Paste")
			(net "M_H_CPU0_SB_DQ<14>")
		)
		(pad "264" smd rect
			(at 2.050034 42.924984 270)
			(size 0.519938 1.4986)
			(layers "F.Cu" "F.Mask" "F.Paste")
			(net "GND")
		)
		(pad "265" smd rect
			(at 2.050034 43.775122 270)
			(size 0.519938 1.4986)
			(layers "F.Cu" "F.Mask" "F.Paste")
			(net "M_H_CPU0_SB_DQ<15>")
		)
		(pad "266" smd rect
			(at 2.050034 44.625006 270)
			(size 0.519938 1.4986)
			(layers "F.Cu" "F.Mask" "F.Paste")
			(net "GND")
		)
		(pad "267" smd rect
			(at 2.050034 45.47489 270)
			(size 0.519938 1.4986)
			(layers "F.Cu" "F.Mask" "F.Paste")
			(net "M_H_CPU0_SB_DQ<18>")
		)
		(pad "268" smd rect
			(at 2.050034 46.325028 270)
			(size 0.519938 1.4986)
			(layers "F.Cu" "F.Mask" "F.Paste")
			(net "GND")
		)
		(pad "269" smd rect
			(at 2.050034 47.174912 270)
			(size 0.519938 1.4986)
			(layers "F.Cu" "F.Mask" "F.Paste")
			(net "M_H_CPU0_SB_DQ<19>")
		)
		(pad "270" smd rect
			(at 2.050034 48.02505 270)
			(size 0.519938 1.4986)
			(layers "F.Cu" "F.Mask" "F.Paste")
			(net "GND")
		)
		(pad "271" smd rect
			(at 2.050034 48.874934 270)
			(size 0.519938 1.4986)
			(layers "F.Cu" "F.Mask" "F.Paste")
			(net "M_H_CPU0_SB_DQS_DN<7>")
		)
		(pad "272" smd rect
			(at 2.050034 49.725072 270)
			(size 0.519938 1.4986)
			(layers "F.Cu" "F.Mask" "F.Paste")
			(net "M_H_CPU0_SB_DQS_DP<7>")
		)
		(pad "273" smd rect
			(at 2.050034 50.574956 270)
			(size 0.519938 1.4986)
			(layers "F.Cu" "F.Mask" "F.Paste")
			(net "GND")
		)
		(pad "274" smd rect
			(at 2.050034 51.425094 270)
			(size 0.519938 1.4986)
			(layers "F.Cu" "F.Mask" "F.Paste")
			(net "M_H_CPU0_SB_DQ<22>")
		)
		(pad "275" smd rect
			(at 2.050034 52.274978 270)
			(size 0.519938 1.4986)
			(layers "F.Cu" "F.Mask" "F.Paste")
			(net "GND")
		)
		(pad "276" smd rect
			(at 2.050034 53.125116 270)
			(size 0.519938 1.4986)
			(layers "F.Cu" "F.Mask" "F.Paste")
			(net "M_H_CPU0_SB_DQ<23>")
		)
		(pad "277" smd rect
			(at 2.050034 53.975 270)
			(size 0.519938 1.4986)
			(layers "F.Cu" "F.Mask" "F.Paste")
			(net "GND")
		)
		(pad "278" smd rect
			(at 2.050034 54.824884 270)
			(size 0.519938 1.4986)
			(layers "F.Cu" "F.Mask" "F.Paste")
			(net "M_H_CPU0_SB_DQ<26>")
		)
		(pad "279" smd rect
			(at 2.050034 55.675022 270)
			(size 0.519938 1.4986)
			(layers "F.Cu" "F.Mask" "F.Paste")
			(net "GND")
		)
		(pad "280" smd rect
			(at 2.050034 56.524906 270)
			(size 0.519938 1.4986)
			(layers "F.Cu" "F.Mask" "F.Paste")
			(net "M_H_CPU0_SB_DQ<27>")
		)
		(pad "281" smd rect
			(at 2.050034 57.375044 270)
			(size 0.519938 1.4986)
			(layers "F.Cu" "F.Mask" "F.Paste")
			(net "GND")
		)
		(pad "282" smd rect
			(at 2.050034 58.224928 270)
			(size 0.519938 1.4986)
			(layers "F.Cu" "F.Mask" "F.Paste")
			(net "M_H_CPU0_SB_DQS_DN<8>")
		)
		(pad "283" smd rect
			(at 2.050034 59.075066 270)
			(size 0.519938 1.4986)
			(layers "F.Cu" "F.Mask" "F.Paste")
			(net "M_H_CPU0_SB_DQS_DP<8>")
		)
		(pad "284" smd rect
			(at 2.050034 59.92495 270)
			(size 0.519938 1.4986)
			(layers "F.Cu" "F.Mask" "F.Paste")
			(net "GND")
		)
		(pad "285" smd rect
			(at 2.050034 60.775088 270)
			(size 0.519938 1.4986)
			(layers "F.Cu" "F.Mask" "F.Paste")
			(net "M_H_CPU0_SB_DQ<30>")
		)
		(pad "286" smd rect
			(at 2.050034 61.624972 270)
			(size 0.519938 1.4986)
			(layers "F.Cu" "F.Mask" "F.Paste")
			(net "GND")
		)
		(pad "287" smd rect
			(at 2.050034 62.47511 270)
			(size 0.519938 1.4986)
			(layers "F.Cu" "F.Mask" "F.Paste")
			(net "M_H_CPU0_SB_DQ<31>")
		)
		(pad "288" smd rect
			(at 2.050034 63.324994 270)
			(size 0.519938 1.4986)
			(layers "F.Cu" "F.Mask" "F.Paste")
			(net "GND")
		)
		(pad "G1" thru_hole oval
			(at 0 -68.97497)
			(size 2.8194 1.5748)
			(drill oval 2.4384 1.1938)
			(layers "*.Cu" "*.Mask")
			(remove_unused_layers no)
			(net "GND")
			(clearance 0.127)
			(thermal_gap 0.127)
		)
		(pad "G2" thru_hole oval
			(at 0 3.875024)
			(size 2.8194 1.5748)
			(drill oval 2.4384 1.1938)
			(layers "*.Cu" "*.Mask")
			(remove_unused_layers no)
			(net "GND")
			(clearance 0.127)
			(thermal_gap 0.127)
		)
		(pad "G3" thru_hole oval
			(at 0 68.97497)
			(size 2.8194 1.5748)
			(drill oval 2.4384 1.1938)
			(layers "*.Cu" "*.Mask")
			(remove_unused_layers no)
			(net "GND")
			(clearance 0.127)
			(thermal_gap 0.127)
		)
	)
)
